(kicad_pcb
	(version 20260206)
	(generator "pcbnew")
	(generator_version "10.0")
	(general
		(thickness 1.6)
		(legacy_teardrops no)
	)
	(paper "A4")
	(title_block
		(title "04192023_DAF0TMB3IC0_F0TG_MB_C_brd_V02_OCP.brd")
		(comment 1 "Grand Teton / footprints 7711-7717 of 8354")
	)
	(layers
		(0 "F.Cu" signal "TOP")
		(4 "In1.Cu" signal "GND")
		(6 "In2.Cu" signal "IN1")
		(8 "In3.Cu" signal "GND1")
		(10 "In4.Cu" signal "IN2")
		(12 "In5.Cu" signal "GND2")
		(14 "In6.Cu" signal "IN3")
		(16 "In7.Cu" signal "GND3")
		(18 "In8.Cu" signal "VCC")
		(20 "In9.Cu" signal "VCC1")
		(22 "In10.Cu" signal "GND4")
		(24 "In11.Cu" signal "IN4")
		(26 "In12.Cu" signal "GND5")
		(28 "In13.Cu" signal "IN5")
		(30 "In14.Cu" signal "GND6")
		(32 "In15.Cu" signal "IN6")
		(34 "In16.Cu" signal "GND7")
		(2 "B.Cu" signal "BOTTOM")
		(9 "F.Adhes" user "F.Adhesive")
		(11 "B.Adhes" user "B.Adhesive")
		(13 "F.Paste" user "Package Geometry/Pastemask Top")
		(15 "B.Paste" user "Package Geometry/Pastemask Bottom")
		(5 "F.SilkS" user "Ref Des/Silkscreen Top")
		(7 "B.SilkS" user "Ref Des/Silkscreen Bottom")
		(1 "F.Mask" user "Board Geometry/Soldermask Top")
		(3 "B.Mask" user "Board Geometry/Soldermask Bottom")
		(17 "Dwgs.User" user "User.Drawings")
		(19 "Cmts.User" user "User.Comments")
		(21 "Eco1.User" user "User.Eco1")
		(23 "Eco2.User" user "User.Eco2")
		(25 "Edge.Cuts" user "Board Geometry/Outline")
		(27 "Margin" user)
		(31 "F.CrtYd" user "Package Geometry/Place Bound Top")
		(29 "B.CrtYd" user "Package Geometry/Place Bound Bottom")
		(35 "F.Fab" user "Ref Des/Assembly Top")
		(33 "B.Fab" user "Ref Des/Assembly Bottom")
	)
	(footprint ""
		(layer "B.Cu")
		(at 140.168376 -386.745988 -90)
		(property "Reference" "C436"
			(at 0 0 90)
			(layer "B.SilkS")
			(hide yes)
			(effects
				(font
					(size 1.27 1.27)
				)
				(justify mirror)
			)
		)
		(property "Value" ""
			(at 0 0 90)
			(layer "B.Fab")
			(effects
				(font
					(size 1.27 1.27)
				)
				(justify mirror)
			)
		)
		(duplicate_pad_numbers_are_jumpers no)
		(fp_line
			(start -0.7874 0.4064)
			(end 0.7874 0.4064)
			(stroke
				(width 0.1524)
				(type default)
			)
			(layer "B.SilkS")
		)
		(fp_line
			(start 0.7874 0.4064)
			(end 0.7874 -0.4064)
			(stroke
				(width 0.1524)
				(type default)
			)
			(layer "B.SilkS")
		)
		(fp_line
			(start -0.7874 -0.4064)
			(end -0.7874 0.4064)
			(stroke
				(width 0.1524)
				(type default)
			)
			(layer "B.SilkS")
		)
		(fp_line
			(start 0.7874 -0.4064)
			(end -0.7874 -0.4064)
			(stroke
				(width 0.1524)
				(type default)
			)
			(layer "B.SilkS")
		)
		(fp_line
			(start -0.67945 0.3048)
			(end -0.120396 0.3048)
			(stroke
				(width 0.1)
				(type default)
			)
			(layer "B.Fab")
		)
		(fp_line
			(start -0.120396 0.3048)
			(end -0.120396 0.2794)
			(stroke
				(width 0.1)
				(type default)
			)
			(layer "B.Fab")
		)
		(fp_line
			(start 0.12065 0.3048)
			(end 0.67945 0.3048)
			(stroke
				(width 0.1)
				(type default)
			)
			(layer "B.Fab")
		)
		(fp_line
			(start 0.67945 0.3048)
			(end 0.67945 -0.305054)
			(stroke
				(width 0.1)
				(type default)
			)
			(layer "B.Fab")
		)
		(fp_line
			(start -0.120396 0.2794)
			(end 0.12065 0.2794)
			(stroke
				(width 0.1)
				(type default)
			)
			(layer "B.Fab")
		)
		(fp_line
			(start 0.12065 0.2794)
			(end 0.12065 0.3048)
			(stroke
				(width 0.1)
				(type default)
			)
			(layer "B.Fab")
		)
		(fp_line
			(start -0.12065 -0.2794)
			(end -0.12065 -0.3048)
			(stroke
				(width 0.1)
				(type default)
			)
			(layer "B.Fab")
		)
		(fp_line
			(start 0.12065 -0.2794)
			(end -0.12065 -0.2794)
			(stroke
				(width 0.1)
				(type default)
			)
			(layer "B.Fab")
		)
		(fp_line
			(start -0.67945 -0.3048)
			(end -0.67945 0.3048)
			(stroke
				(width 0.1)
				(type default)
			)
			(layer "B.Fab")
		)
		(fp_line
			(start -0.12065 -0.3048)
			(end -0.67945 -0.3048)
			(stroke
				(width 0.1)
				(type default)
			)
			(layer "B.Fab")
		)
		(fp_line
			(start 0.12065 -0.305054)
			(end 0.12065 -0.2794)
			(stroke
				(width 0.1)
				(type default)
			)
			(layer "B.Fab")
		)
		(fp_line
			(start 0.67945 -0.305054)
			(end 0.12065 -0.305054)
			(stroke
				(width 0.1)
				(type default)
			)
			(layer "B.Fab")
		)
		(pad "1" smd circle
			(at 0.40005 0 90)
			(size 0 0)
			(layers "B.Cu" "B.Mask" "B.Paste")
			(net "P1V8_CPU1_RT_1D")
		)
		(pad "2" smd circle
			(at -0.40005 0 90)
			(size 0 0)
			(layers "B.Cu" "B.Mask" "B.Paste")
			(net "GND")
		)
	)
	(footprint ""
		(layer "B.Cu")
		(at 358.216454 -267.52931)
		(property "Reference" "C2240"
			(at 0 0 0)
			(layer "B.SilkS")
			(hide yes)
			(effects
				(font
					(size 1.27 1.27)
				)
				(justify mirror)
			)
		)
		(property "Value" ""
			(at 0 0 0)
			(layer "B.Fab")
			(effects
				(font
					(size 1.27 1.27)
				)
				(justify mirror)
			)
		)
		(duplicate_pad_numbers_are_jumpers no)
		(fp_line
			(start -0.7874 -0.4064)
			(end -0.7874 0.4064)
			(stroke
				(width 0.1524)
				(type default)
			)
			(layer "B.SilkS")
		)
		(fp_line
			(start -0.7874 0.4064)
			(end 0.7874 0.4064)
			(stroke
				(width 0.1524)
				(type default)
			)
			(layer "B.SilkS")
		)
		(fp_line
			(start 0.7874 -0.4064)
			(end -0.7874 -0.4064)
			(stroke
				(width 0.1524)
				(type default)
			)
			(layer "B.SilkS")
		)
		(fp_line
			(start 0.7874 0.4064)
			(end 0.7874 -0.4064)
			(stroke
				(width 0.1524)
				(type default)
			)
			(layer "B.SilkS")
		)
		(fp_line
			(start -0.67945 -0.3048)
			(end -0.67945 0.3048)
			(stroke
				(width 0.1)
				(type default)
			)
			(layer "B.Fab")
		)
		(fp_line
			(start -0.67945 0.3048)
			(end -0.120396 0.3048)
			(stroke
				(width 0.1)
				(type default)
			)
			(layer "B.Fab")
		)
		(fp_line
			(start -0.12065 -0.3048)
			(end -0.67945 -0.3048)
			(stroke
				(width 0.1)
				(type default)
			)
			(layer "B.Fab")
		)
		(fp_line
			(start -0.12065 -0.2794)
			(end -0.12065 -0.3048)
			(stroke
				(width 0.1)
				(type default)
			)
			(layer "B.Fab")
		)
		(fp_line
			(start -0.120396 0.2794)
			(end 0.12065 0.2794)
			(stroke
				(width 0.1)
				(type default)
			)
			(layer "B.Fab")
		)
		(fp_line
			(start -0.120396 0.3048)
			(end -0.120396 0.2794)
			(stroke
				(width 0.1)
				(type default)
			)
			(layer "B.Fab")
		)
		(fp_line
			(start 0.12065 -0.305054)
			(end 0.12065 -0.2794)
			(stroke
				(width 0.1)
				(type default)
			)
			(layer "B.Fab")
		)
		(fp_line
			(start 0.12065 -0.2794)
			(end -0.12065 -0.2794)
			(stroke
				(width 0.1)
				(type default)
			)
			(layer "B.Fab")
		)
		(fp_line
			(start 0.12065 0.2794)
			(end 0.12065 0.3048)
			(stroke
				(width 0.1)
				(type default)
			)
			(layer "B.Fab")
		)
		(fp_line
			(start 0.12065 0.3048)
			(end 0.67945 0.3048)
			(stroke
				(width 0.1)
				(type default)
			)
			(layer "B.Fab")
		)
		(fp_line
			(start 0.67945 -0.305054)
			(end 0.12065 -0.305054)
			(stroke
				(width 0.1)
				(type default)
			)
			(layer "B.Fab")
		)
		(fp_line
			(start 0.67945 0.3048)
			(end 0.67945 -0.305054)
			(stroke
				(width 0.1)
				(type default)
			)
			(layer "B.Fab")
		)
		(pad "1" smd circle
			(at 0.40005 0 180)
			(size 0 0)
			(layers "B.Cu" "B.Mask" "B.Paste")
			(net "PVDDCR_CPU1_P0")
		)
		(pad "2" smd circle
			(at -0.40005 0 180)
			(size 0 0)
			(layers "B.Cu" "B.Mask" "B.Paste")
			(net "GND")
		)
	)
	(footprint ""
		(layer "B.Cu")
		(at 133.506972 -41.007792 90)
		(property "Reference" "C6032"
			(at 0 0 90)
			(layer "B.SilkS")
			(hide yes)
			(effects
				(font
					(size 1.27 1.27)
				)
				(justify mirror)
			)
		)
		(property "Value" ""
			(at 0 0 90)
			(layer "B.Fab")
			(effects
				(font
					(size 1.27 1.27)
				)
				(justify mirror)
			)
		)
		(duplicate_pad_numbers_are_jumpers no)
		(fp_line
			(start 0.7874 -0.4064)
			(end -0.7874 -0.4064)
			(stroke
				(width 0.1524)
				(type default)
			)
			(layer "B.SilkS")
		)
		(fp_line
			(start -0.7874 -0.4064)
			(end -0.7874 0.4064)
			(stroke
				(width 0.1524)
				(type default)
			)
			(layer "B.SilkS")
		)
		(fp_line
			(start 0.7874 0.4064)
			(end 0.7874 -0.4064)
			(stroke
				(width 0.1524)
				(type default)
			)
			(layer "B.SilkS")
		)
		(fp_line
			(start -0.7874 0.4064)
			(end 0.7874 0.4064)
			(stroke
				(width 0.1524)
				(type default)
			)
			(layer "B.SilkS")
		)
		(fp_line
			(start 0.67945 -0.305054)
			(end 0.12065 -0.305054)
			(stroke
				(width 0.1)
				(type default)
			)
			(layer "B.Fab")
		)
		(fp_line
			(start 0.12065 -0.305054)
			(end 0.12065 -0.2794)
			(stroke
				(width 0.1)
				(type default)
			)
			(layer "B.Fab")
		)
		(fp_line
			(start -0.12065 -0.3048)
			(end -0.67945 -0.3048)
			(stroke
				(width 0.1)
				(type default)
			)
			(layer "B.Fab")
		)
		(fp_line
			(start -0.67945 -0.3048)
			(end -0.67945 0.3048)
			(stroke
				(width 0.1)
				(type default)
			)
			(layer "B.Fab")
		)
		(fp_line
			(start 0.12065 -0.2794)
			(end -0.12065 -0.2794)
			(stroke
				(width 0.1)
				(type default)
			)
			(layer "B.Fab")
		)
		(fp_line
			(start -0.12065 -0.2794)
			(end -0.12065 -0.3048)
			(stroke
				(width 0.1)
				(type default)
			)
			(layer "B.Fab")
		)
		(fp_line
			(start 0.12065 0.2794)
			(end 0.12065 0.3048)
			(stroke
				(width 0.1)
				(type default)
			)
			(layer "B.Fab")
		)
		(fp_line
			(start -0.120396 0.2794)
			(end 0.12065 0.2794)
			(stroke
				(width 0.1)
				(type default)
			)
			(layer "B.Fab")
		)
		(fp_line
			(start 0.67945 0.3048)
			(end 0.67945 -0.305054)
			(stroke
				(width 0.1)
				(type default)
			)
			(layer "B.Fab")
		)
		(fp_line
			(start 0.12065 0.3048)
			(end 0.67945 0.3048)
			(stroke
				(width 0.1)
				(type default)
			)
			(layer "B.Fab")
		)
		(fp_line
			(start -0.120396 0.3048)
			(end -0.120396 0.2794)
			(stroke
				(width 0.1)
				(type default)
			)
			(layer "B.Fab")
		)
		(fp_line
			(start -0.67945 0.3048)
			(end -0.120396 0.3048)
			(stroke
				(width 0.1)
				(type default)
			)
			(layer "B.Fab")
		)
		(pad "1" smd circle
			(at 0.40005 0 270)
			(size 0 0)
			(layers "B.Cu" "B.Mask" "B.Paste")
			(net "P1V2_CPU0_USB_DVDD12")
		)
		(pad "2" smd circle
			(at -0.40005 0 270)
			(size 0 0)
			(layers "B.Cu" "B.Mask" "B.Paste")
			(net "GND")
		)
	)
	(footprint ""
		(layer "B.Cu")
		(at 461.498188 -389.132064 -90)
		(property "Reference" "PC6567_1"
			(at 0 0 90)
			(layer "B.SilkS")
			(hide yes)
			(effects
				(font
					(size 1.27 1.27)
				)
				(justify mirror)
			)
		)
		(property "Value" ""
			(at 0 0 90)
			(layer "B.Fab")
			(effects
				(font
					(size 1.27 1.27)
				)
				(justify mirror)
			)
		)
		(duplicate_pad_numbers_are_jumpers no)
		(fp_line
			(start -1.524 0.762)
			(end 1.524 0.762)
			(stroke
				(width 0.1524)
				(type default)
			)
			(layer "B.SilkS")
		)
		(fp_line
			(start 1.524 0.762)
			(end 1.524 -0.762)
			(stroke
				(width 0.1524)
				(type default)
			)
			(layer "B.SilkS")
		)
		(fp_line
			(start -1.524 -0.762)
			(end -1.524 0.762)
			(stroke
				(width 0.1524)
				(type default)
			)
			(layer "B.SilkS")
		)
		(fp_line
			(start 1.524 -0.762)
			(end -1.524 -0.762)
			(stroke
				(width 0.1524)
				(type default)
			)
			(layer "B.SilkS")
		)
		(fp_line
			(start -1.1049 0.724916)
			(end -1.1049 -0.724916)
			(stroke
				(width 0.1)
				(type default)
			)
			(layer "B.Fab")
		)
		(fp_line
			(start 1.1049 0.724916)
			(end -1.1049 0.724916)
			(stroke
				(width 0.1)
				(type default)
			)
			(layer "B.Fab")
		)
		(fp_line
			(start -1.1049 -0.724916)
			(end 1.1049 -0.724916)
			(stroke
				(width 0.1)
				(type default)
			)
			(layer "B.Fab")
		)
		(fp_line
			(start 1.1049 -0.724916)
			(end 1.1049 0.724916)
			(stroke
				(width 0.1)
				(type default)
			)
			(layer "B.Fab")
		)
		(pad "1" smd rect
			(at 0.889 0 270)
			(size 1.016 1.27)
			(layers "B.Cu" "B.Mask" "B.Paste")
			(net "P0V9_CPU0_RT_2D")
		)
		(pad "2" smd rect
			(at -0.889 0 270)
			(size 1.016 1.27)
			(layers "B.Cu" "B.Mask" "B.Paste")
			(net "GND")
		)
	)
	(footprint ""
		(layer "B.Cu")
		(at 447.237866 -407.6573)
		(property "Reference" "PC6816"
			(at 0 0 0)
			(layer "B.SilkS")
			(hide yes)
			(effects
				(font
					(size 1.27 1.27)
				)
				(justify mirror)
			)
		)
		(property "Value" ""
			(at 0 0 0)
			(layer "B.Fab")
			(effects
				(font
					(size 1.27 1.27)
				)
				(justify mirror)
			)
		)
		(duplicate_pad_numbers_are_jumpers no)
		(fp_line
			(start -1.524 -0.762)
			(end -1.524 0.762)
			(stroke
				(width 0.1524)
				(type default)
			)
			(layer "B.SilkS")
		)
		(fp_line
			(start -1.524 0.762)
			(end 1.524 0.762)
			(stroke
				(width 0.1524)
				(type default)
			)
			(layer "B.SilkS")
		)
		(fp_line
			(start 1.524 -0.762)
			(end -1.524 -0.762)
			(stroke
				(width 0.1524)
				(type default)
			)
			(layer "B.SilkS")
		)
		(fp_line
			(start 1.524 0.762)
			(end 1.524 -0.762)
			(stroke
				(width 0.1524)
				(type default)
			)
			(layer "B.SilkS")
		)
		(fp_line
			(start -1.1049 -0.724916)
			(end 1.1049 -0.724916)
			(stroke
				(width 0.1)
				(type default)
			)
			(layer "B.Fab")
		)
		(fp_line
			(start -1.1049 0.724916)
			(end -1.1049 -0.724916)
			(stroke
				(width 0.1)
				(type default)
			)
			(layer "B.Fab")
		)
		(fp_line
			(start 1.1049 -0.724916)
			(end 1.1049 0.724916)
			(stroke
				(width 0.1)
				(type default)
			)
			(layer "B.Fab")
		)
		(fp_line
			(start 1.1049 0.724916)
			(end -1.1049 0.724916)
			(stroke
				(width 0.1)
				(type default)
			)
			(layer "B.Fab")
		)
		(pad "1" smd rect
			(at 0.889 0)
			(size 1.016 1.27)
			(layers "B.Cu" "B.Mask" "B.Paste")
			(net "SW_P12V_AUX_P0V9_RETIMER_CPU0_FLT")
		)
		(pad "2" smd rect
			(at -0.889 0)
			(size 1.016 1.27)
			(layers "B.Cu" "B.Mask" "B.Paste")
			(net "GND")
		)
	)
	(footprint ""
		(layer "B.Cu")
		(at 239.903 -340.741)
		(property "Reference" "R1403"
			(at 0 0 0)
			(layer "B.SilkS")
			(hide yes)
			(effects
				(font
					(size 1.27 1.27)
				)
				(justify mirror)
			)
		)
		(property "Value" ""
			(at 0 0 0)
			(layer "B.Fab")
			(effects
				(font
					(size 1.27 1.27)
				)
				(justify mirror)
			)
		)
		(duplicate_pad_numbers_are_jumpers no)
		(fp_line
			(start -0.32512 -0.175006)
			(end -0.32512 0.175006)
			(stroke
				(width 0.1)
				(type default)
			)
			(layer "B.Fab")
		)
		(fp_line
			(start -0.32512 0.175006)
			(end 0.32512 0.175006)
			(stroke
				(width 0.1)
				(type default)
			)
			(layer "B.Fab")
		)
		(fp_line
			(start 0.32512 -0.175006)
			(end -0.32512 -0.175006)
			(stroke
				(width 0.1)
				(type default)
			)
			(layer "B.Fab")
		)
		(fp_line
			(start 0.32512 0.175006)
			(end 0.32512 -0.175006)
			(stroke
				(width 0.1)
				(type default)
			)
			(layer "B.Fab")
		)
		(pad "1" smd rect
			(at 0.2667 0 180)
			(size 0.3048 0.381)
			(layers "B.Cu" "B.Mask" "B.Paste")
			(net "P1V8_CPU1_RT_1D")
		)
		(pad "2" smd rect
			(at -0.2667 0)
			(size 0.3048 0.381)
			(layers "B.Cu" "B.Mask" "B.Paste")
			(net "SMB_RT_CPU1_P2_ROM_MUX_2D_R_SDA")
		)
	)
	(footprint ""
		(layer "B.Cu")
		(at 59.401202 -195.012564 180)
		(property "Reference" "R1580"
			(at 0 0 0)
			(layer "B.SilkS")
			(hide yes)
			(effects
				(font
					(size 1.27 1.27)
				)
				(justify mirror)
			)
		)
		(property "Value" ""
			(at 0 0 0)
			(layer "B.Fab")
			(effects
				(font
					(size 1.27 1.27)
				)
				(justify mirror)
			)
		)
		(duplicate_pad_numbers_are_jumpers no)
		(fp_line
			(start 0.7874 0.4064)
			(end 0.7874 -0.4064)
			(stroke
				(width 0.1524)
				(type default)
			)
			(layer "B.SilkS")
		)
		(fp_line
			(start 0.7874 -0.4064)
			(end -0.7874 -0.4064)
			(stroke
				(width 0.1524)
				(type default)
			)
			(layer "B.SilkS")
		)
		(fp_line
			(start -0.7874 0.4064)
			(end 0.7874 0.4064)
			(stroke
				(width 0.1524)
				(type default)
			)
			(layer "B.SilkS")
		)
		(fp_line
			(start -0.7874 -0.4064)
			(end -0.7874 0.4064)
			(stroke
				(width 0.1524)
				(type default)
			)
			(layer "B.SilkS")
		)
		(fp_line
			(start 0.67945 0.3048)
			(end 0.67945 -0.305054)
			(stroke
				(width 0.1)
				(type default)
			)
			(layer "B.Fab")
		)
		(fp_line
			(start 0.67945 -0.305054)
			(end 0.12065 -0.305054)
			(stroke
				(width 0.1)
				(type default)
			)
			(layer "B.Fab")
		)
		(fp_line
			(start 0.12065 0.3048)
			(end 0.67945 0.3048)
			(stroke
				(width 0.1)
				(type default)
			)
			(layer "B.Fab")
		)
		(fp_line
			(start 0.12065 0.2794)
			(end 0.12065 0.3048)
			(stroke
				(width 0.1)
				(type default)
			)
			(layer "B.Fab")
		)
		(fp_line
			(start 0.12065 -0.2794)
			(end -0.12065 -0.2794)
			(stroke
				(width 0.1)
				(type default)
			)
			(layer "B.Fab")
		)
		(fp_line
			(start 0.12065 -0.305054)
			(end 0.12065 -0.2794)
			(stroke
				(width 0.1)
				(type default)
			)
			(layer "B.Fab")
		)
		(fp_line
			(start -0.120396 0.3048)
			(end -0.120396 0.2794)
			(stroke
				(width 0.1)
				(type default)
			)
			(layer "B.Fab")
		)
		(fp_line
			(start -0.120396 0.2794)
			(end 0.12065 0.2794)
			(stroke
				(width 0.1)
				(type default)
			)
			(layer "B.Fab")
		)
		(fp_line
			(start -0.12065 -0.2794)
			(end -0.12065 -0.3048)
			(stroke
				(width 0.1)
				(type default)
			)
			(layer "B.Fab")
		)
		(fp_line
			(start -0.12065 -0.3048)
			(end -0.67945 -0.3048)
			(stroke
				(width 0.1)
				(type default)
			)
			(layer "B.Fab")
		)
		(fp_line
			(start -0.67945 0.3048)
			(end -0.120396 0.3048)
			(stroke
				(width 0.1)
				(type default)
			)
			(layer "B.Fab")
		)
		(fp_line
			(start -0.67945 -0.3048)
			(end -0.67945 0.3048)
			(stroke
				(width 0.1)
				(type default)
			)
			(layer "B.Fab")
		)
		(pad "1" smd circle
			(at 0.40005 0)
			(size 0 0)
			(layers "B.Cu" "B.Mask" "B.Paste")
			(net "I3C_SPD_DDRAF_CPU1_SCL")
		)
		(pad "2" smd circle
			(at -0.40005 0)
			(size 0 0)
			(layers "B.Cu" "B.Mask" "B.Paste")
			(net "I3C_SPD_DDRA_CPU1_SCL")
		)
	)
)
